(kicad_pcb
	(version 20260206)
	(generator "pcbnew")
	(generator_version "10.0")
	(general
		(thickness 1.6)
		(legacy_teardrops no)
	)
	(paper "A4")
	(title_block
		(title "03242023_DA0F0TMBIJ0_F0T_Motherboard_J_brd_V01_OCP.brd")
		(comment 1 "Grand Teton / footprints 2986-2992 of 6105")
	)
	(layers
		(0 "F.Cu" signal "TOP")
		(4 "In1.Cu" signal "GND")
		(6 "In2.Cu" signal "IN1")
		(8 "In3.Cu" signal "GND1")
		(10 "In4.Cu" signal "IN2")
		(12 "In5.Cu" signal "GND2")
		(14 "In6.Cu" signal "IN3")
		(16 "In7.Cu" signal "GND3")
		(18 "In8.Cu" signal "VCC")
		(20 "In9.Cu" signal "VCC1")
		(22 "In10.Cu" signal "GND4")
		(24 "In11.Cu" signal "IN4")
		(26 "In12.Cu" signal "GND5")
		(28 "In13.Cu" signal "IN5")
		(30 "In14.Cu" signal "GND6")
		(32 "In15.Cu" signal "IN6")
		(34 "In16.Cu" signal "GND7")
		(2 "B.Cu" signal "BOTTOM")
		(9 "F.Adhes" user "F.Adhesive")
		(11 "B.Adhes" user "B.Adhesive")
		(13 "F.Paste" user "Package Geometry/Pastemask Top")
		(15 "B.Paste" user "Package Geometry/Pastemask Bottom")
		(5 "F.SilkS" user "Ref Des/Silkscreen Top")
		(7 "B.SilkS" user "Ref Des/Silkscreen Bottom")
		(1 "F.Mask" user "Board Geometry/Soldermask Top")
		(3 "B.Mask" user "Board Geometry/Soldermask Bottom")
		(17 "Dwgs.User" user "User.Drawings")
		(19 "Cmts.User" user "User.Comments")
		(21 "Eco1.User" user "User.Eco1")
		(23 "Eco2.User" user "User.Eco2")
		(25 "Edge.Cuts" user "Board Geometry/Outline")
		(27 "Margin" user)
		(31 "F.CrtYd" user "Package Geometry/Place Bound Top")
		(29 "B.CrtYd" user "Package Geometry/Place Bound Bottom")
		(35 "F.Fab" user "Ref Des/Assembly Top")
		(33 "B.Fab" user "Ref Des/Assembly Bottom")
	)
	(footprint ""
		(layer "F.Cu")
		(at 32.191452 -166.777162)
		(property "Reference" "PC390"
			(at 0 0 0)
			(layer "F.SilkS")
			(hide yes)
			(effects
				(font
					(size 1.27 1.27)
				)
			)
		)
		(property "Value" ""
			(at 0 0 0)
			(layer "F.Fab")
			(effects
				(font
					(size 1.27 1.27)
				)
			)
		)
		(duplicate_pad_numbers_are_jumpers no)
		(fp_line
			(start -0.7874 -0.4064)
			(end 0.7874 -0.4064)
			(stroke
				(width 0.1524)
				(type default)
			)
			(layer "F.SilkS")
		)
		(fp_line
			(start -0.7874 0.4064)
			(end -0.7874 -0.4064)
			(stroke
				(width 0.1524)
				(type default)
			)
			(layer "F.SilkS")
		)
		(fp_line
			(start 0.7874 -0.4064)
			(end 0.7874 0.4064)
			(stroke
				(width 0.1524)
				(type default)
			)
			(layer "F.SilkS")
		)
		(fp_line
			(start 0.7874 0.4064)
			(end -0.7874 0.4064)
			(stroke
				(width 0.1524)
				(type default)
			)
			(layer "F.SilkS")
		)
		(fp_line
			(start -0.67945 -0.305054)
			(end -0.12065 -0.305054)
			(stroke
				(width 0.1)
				(type default)
			)
			(layer "F.Fab")
		)
		(fp_line
			(start -0.67945 0.3048)
			(end -0.67945 -0.305054)
			(stroke
				(width 0.1)
				(type default)
			)
			(layer "F.Fab")
		)
		(fp_line
			(start -0.12065 -0.305054)
			(end -0.12065 -0.2794)
			(stroke
				(width 0.1)
				(type default)
			)
			(layer "F.Fab")
		)
		(fp_line
			(start -0.12065 -0.2794)
			(end 0.12065 -0.2794)
			(stroke
				(width 0.1)
				(type default)
			)
			(layer "F.Fab")
		)
		(fp_line
			(start -0.12065 0.2794)
			(end -0.12065 0.3048)
			(stroke
				(width 0.1)
				(type default)
			)
			(layer "F.Fab")
		)
		(fp_line
			(start -0.12065 0.3048)
			(end -0.67945 0.3048)
			(stroke
				(width 0.1)
				(type default)
			)
			(layer "F.Fab")
		)
		(fp_line
			(start 0.120396 0.2794)
			(end -0.12065 0.2794)
			(stroke
				(width 0.1)
				(type default)
			)
			(layer "F.Fab")
		)
		(fp_line
			(start 0.120396 0.3048)
			(end 0.120396 0.2794)
			(stroke
				(width 0.1)
				(type default)
			)
			(layer "F.Fab")
		)
		(fp_line
			(start 0.12065 -0.3048)
			(end 0.67945 -0.3048)
			(stroke
				(width 0.1)
				(type default)
			)
			(layer "F.Fab")
		)
		(fp_line
			(start 0.12065 -0.2794)
			(end 0.12065 -0.3048)
			(stroke
				(width 0.1)
				(type default)
			)
			(layer "F.Fab")
		)
		(fp_line
			(start 0.67945 -0.3048)
			(end 0.67945 0.3048)
			(stroke
				(width 0.1)
				(type default)
			)
			(layer "F.Fab")
		)
		(fp_line
			(start 0.67945 0.3048)
			(end 0.120396 0.3048)
			(stroke
				(width 0.1)
				(type default)
			)
			(layer "F.Fab")
		)
		(pad "1" smd circle
			(at -0.40005 0)
			(size 0 0)
			(layers "F.Cu" "F.Mask" "F.Paste")
			(net "PVCCD_HV_CPU1_ISENSE_N")
		)
		(pad "2" smd circle
			(at 0.40005 0)
			(size 0 0)
			(layers "F.Cu" "F.Mask" "F.Paste")
			(net "GND")
		)
	)
	(footprint ""
		(layer "F.Cu")
		(at 393.115038 -31.185612 90)
		(property "Reference" "R1595"
			(at 0 0 90)
			(layer "F.SilkS")
			(hide yes)
			(effects
				(font
					(size 1.27 1.27)
				)
			)
		)
		(property "Value" ""
			(at 0 0 90)
			(layer "F.Fab")
			(effects
				(font
					(size 1.27 1.27)
				)
			)
		)
		(duplicate_pad_numbers_are_jumpers no)
		(fp_line
			(start 0.7874 -0.4064)
			(end 0.7874 0.4064)
			(stroke
				(width 0.1524)
				(type default)
			)
			(layer "F.SilkS")
		)
		(fp_line
			(start -0.7874 -0.4064)
			(end 0.7874 -0.4064)
			(stroke
				(width 0.1524)
				(type default)
			)
			(layer "F.SilkS")
		)
		(fp_line
			(start 0.7874 0.4064)
			(end -0.7874 0.4064)
			(stroke
				(width 0.1524)
				(type default)
			)
			(layer "F.SilkS")
		)
		(fp_line
			(start -0.7874 0.4064)
			(end -0.7874 -0.4064)
			(stroke
				(width 0.1524)
				(type default)
			)
			(layer "F.SilkS")
		)
		(fp_line
			(start -0.12065 -0.305054)
			(end -0.12065 -0.2794)
			(stroke
				(width 0.1)
				(type default)
			)
			(layer "F.Fab")
		)
		(fp_line
			(start -0.67945 -0.305054)
			(end -0.12065 -0.305054)
			(stroke
				(width 0.1)
				(type default)
			)
			(layer "F.Fab")
		)
		(fp_line
			(start 0.67945 -0.3048)
			(end 0.67945 0.3048)
			(stroke
				(width 0.1)
				(type default)
			)
			(layer "F.Fab")
		)
		(fp_line
			(start 0.12065 -0.3048)
			(end 0.67945 -0.3048)
			(stroke
				(width 0.1)
				(type default)
			)
			(layer "F.Fab")
		)
		(fp_line
			(start 0.12065 -0.2794)
			(end 0.12065 -0.3048)
			(stroke
				(width 0.1)
				(type default)
			)
			(layer "F.Fab")
		)
		(fp_line
			(start -0.12065 -0.2794)
			(end 0.12065 -0.2794)
			(stroke
				(width 0.1)
				(type default)
			)
			(layer "F.Fab")
		)
		(fp_line
			(start 0.120396 0.2794)
			(end -0.12065 0.2794)
			(stroke
				(width 0.1)
				(type default)
			)
			(layer "F.Fab")
		)
		(fp_line
			(start -0.12065 0.2794)
			(end -0.12065 0.3048)
			(stroke
				(width 0.1)
				(type default)
			)
			(layer "F.Fab")
		)
		(fp_line
			(start 0.67945 0.3048)
			(end 0.120396 0.3048)
			(stroke
				(width 0.1)
				(type default)
			)
			(layer "F.Fab")
		)
		(fp_line
			(start 0.120396 0.3048)
			(end 0.120396 0.2794)
			(stroke
				(width 0.1)
				(type default)
			)
			(layer "F.Fab")
		)
		(fp_line
			(start -0.12065 0.3048)
			(end -0.67945 0.3048)
			(stroke
				(width 0.1)
				(type default)
			)
			(layer "F.Fab")
		)
		(fp_line
			(start -0.67945 0.3048)
			(end -0.67945 -0.305054)
			(stroke
				(width 0.1)
				(type default)
			)
			(layer "F.Fab")
		)
		(pad "1" smd circle
			(at -0.40005 0 90)
			(size 0 0)
			(layers "F.Cu" "F.Mask" "F.Paste")
			(net "OCP_SFF_PWRBRK_BUFF_N")
		)
		(pad "2" smd circle
			(at 0.40005 0 90)
			(size 0 0)
			(layers "F.Cu" "F.Mask" "F.Paste")
			(net "OCP_SFF_PWRBRK_N")
		)
	)
	(footprint ""
		(layer "F.Cu")
		(at 359.71988 -294.01008 180)
		(property "Reference" "C215"
			(at 0 0 180)
			(layer "F.SilkS")
			(hide yes)
			(effects
				(font
					(size 1.27 1.27)
				)
			)
		)
		(property "Value" ""
			(at 0 0 180)
			(layer "F.Fab")
			(effects
				(font
					(size 1.27 1.27)
				)
			)
		)
		(duplicate_pad_numbers_are_jumpers no)
		(fp_line
			(start 1.524 0.762)
			(end -1.524 0.762)
			(stroke
				(width 0.1524)
				(type default)
			)
			(layer "F.SilkS")
		)
		(fp_line
			(start 1.524 -0.762)
			(end 1.524 0.762)
			(stroke
				(width 0.1524)
				(type default)
			)
			(layer "F.SilkS")
		)
		(fp_line
			(start -1.524 0.762)
			(end -1.524 -0.762)
			(stroke
				(width 0.1524)
				(type default)
			)
			(layer "F.SilkS")
		)
		(fp_line
			(start -1.524 -0.762)
			(end 1.524 -0.762)
			(stroke
				(width 0.1524)
				(type default)
			)
			(layer "F.SilkS")
		)
		(fp_line
			(start 1.1049 0.724916)
			(end 1.1049 -0.724916)
			(stroke
				(width 0.1)
				(type default)
			)
			(layer "F.Fab")
		)
		(fp_line
			(start 1.1049 -0.724916)
			(end -1.1049 -0.724916)
			(stroke
				(width 0.1)
				(type default)
			)
			(layer "F.Fab")
		)
		(fp_line
			(start -1.1049 0.724916)
			(end 1.1049 0.724916)
			(stroke
				(width 0.1)
				(type default)
			)
			(layer "F.Fab")
		)
		(fp_line
			(start -1.1049 -0.724916)
			(end -1.1049 0.724916)
			(stroke
				(width 0.1)
				(type default)
			)
			(layer "F.Fab")
		)
		(pad "1" smd rect
			(at -0.889 0)
			(size 1.016 1.27)
			(layers "F.Cu" "F.Mask" "F.Paste")
			(net "PVCCIN_CPU0")
		)
		(pad "2" smd rect
			(at 0.889 0)
			(size 1.016 1.27)
			(layers "F.Cu" "F.Mask" "F.Paste")
			(net "GND")
		)
	)
	(footprint ""
		(layer "F.Cu")
		(at 183.198008 -398.651222 180)
		(property "Reference" "PC2190"
			(at 0 0 180)
			(layer "F.SilkS")
			(hide yes)
			(effects
				(font
					(size 1.27 1.27)
				)
			)
		)
		(property "Value" ""
			(at 0 0 180)
			(layer "F.Fab")
			(effects
				(font
					(size 1.27 1.27)
				)
			)
		)
		(duplicate_pad_numbers_are_jumpers no)
		(fp_line
			(start 0.7874 0.4064)
			(end -0.7874 0.4064)
			(stroke
				(width 0.1524)
				(type default)
			)
			(layer "F.SilkS")
		)
		(fp_line
			(start 0.7874 -0.4064)
			(end 0.7874 0.4064)
			(stroke
				(width 0.1524)
				(type default)
			)
			(layer "F.SilkS")
		)
		(fp_line
			(start -0.7874 0.4064)
			(end -0.7874 -0.4064)
			(stroke
				(width 0.1524)
				(type default)
			)
			(layer "F.SilkS")
		)
		(fp_line
			(start -0.7874 -0.4064)
			(end 0.7874 -0.4064)
			(stroke
				(width 0.1524)
				(type default)
			)
			(layer "F.SilkS")
		)
		(fp_line
			(start 0.67945 0.3048)
			(end 0.120396 0.3048)
			(stroke
				(width 0.1)
				(type default)
			)
			(layer "F.Fab")
		)
		(fp_line
			(start 0.67945 -0.3048)
			(end 0.67945 0.3048)
			(stroke
				(width 0.1)
				(type default)
			)
			(layer "F.Fab")
		)
		(fp_line
			(start 0.12065 -0.2794)
			(end 0.12065 -0.3048)
			(stroke
				(width 0.1)
				(type default)
			)
			(layer "F.Fab")
		)
		(fp_line
			(start 0.12065 -0.3048)
			(end 0.67945 -0.3048)
			(stroke
				(width 0.1)
				(type default)
			)
			(layer "F.Fab")
		)
		(fp_line
			(start 0.120396 0.3048)
			(end 0.120396 0.2794)
			(stroke
				(width 0.1)
				(type default)
			)
			(layer "F.Fab")
		)
		(fp_line
			(start 0.120396 0.2794)
			(end -0.12065 0.2794)
			(stroke
				(width 0.1)
				(type default)
			)
			(layer "F.Fab")
		)
		(fp_line
			(start -0.12065 0.3048)
			(end -0.67945 0.3048)
			(stroke
				(width 0.1)
				(type default)
			)
			(layer "F.Fab")
		)
		(fp_line
			(start -0.12065 0.2794)
			(end -0.12065 0.3048)
			(stroke
				(width 0.1)
				(type default)
			)
			(layer "F.Fab")
		)
		(fp_line
			(start -0.12065 -0.2794)
			(end 0.12065 -0.2794)
			(stroke
				(width 0.1)
				(type default)
			)
			(layer "F.Fab")
		)
		(fp_line
			(start -0.12065 -0.305054)
			(end -0.12065 -0.2794)
			(stroke
				(width 0.1)
				(type default)
			)
			(layer "F.Fab")
		)
		(fp_line
			(start -0.67945 0.3048)
			(end -0.67945 -0.305054)
			(stroke
				(width 0.1)
				(type default)
			)
			(layer "F.Fab")
		)
		(fp_line
			(start -0.67945 -0.305054)
			(end -0.12065 -0.305054)
			(stroke
				(width 0.1)
				(type default)
			)
			(layer "F.Fab")
		)
		(pad "1" smd circle
			(at -0.40005 0 180)
			(size 0 0)
			(layers "F.Cu" "F.Mask" "F.Paste")
			(net "HSC_VOSEN")
		)
		(pad "2" smd circle
			(at 0.40005 0 180)
			(size 0 0)
			(layers "F.Cu" "F.Mask" "F.Paste")
			(net "AGND_HSC")
		)
	)
	(footprint ""
		(layer "F.Cu")
		(at 364.940342 -390.48817)
		(property "Reference" "Q137"
			(at 2.02692 0.708152 0)
			(unlocked yes)
			(layer "F.SilkS")
			(effects
				(font
					(size 0.7874 0.5842)
					(thickness 0.1524)
				)
				(justify left)
			)
		)
		(property "Value" ""
			(at 0 0 0)
			(layer "F.Fab")
			(effects
				(font
					(size 1.27 1.27)
				)
			)
		)
		(duplicate_pad_numbers_are_jumpers no)
		(fp_line
			(start -1.332738 -1.100074)
			(end -0.4826 -1.100074)
			(stroke
				(width 0.1524)
				(type default)
			)
			(layer "F.SilkS")
		)
		(fp_line
			(start -1.332738 1.100074)
			(end -1.332738 -1.100074)
			(stroke
				(width 0.1524)
				(type default)
			)
			(layer "F.SilkS")
		)
		(fp_line
			(start -0.4826 -1.100074)
			(end 0 -0.541274)
			(stroke
				(width 0.1524)
				(type default)
			)
			(layer "F.SilkS")
		)
		(fp_line
			(start 0 -0.541274)
			(end 0.4826 -1.100074)
			(stroke
				(width 0.1524)
				(type default)
			)
			(layer "F.SilkS")
		)
		(fp_line
			(start 0.4826 -1.100074)
			(end 1.332738 -1.100074)
			(stroke
				(width 0.1524)
				(type default)
			)
			(layer "F.SilkS")
		)
		(fp_line
			(start 1.332738 -1.100074)
			(end 1.332738 1.100074)
			(stroke
				(width 0.1524)
				(type default)
			)
			(layer "F.SilkS")
		)
		(fp_line
			(start 1.332738 1.100074)
			(end -1.332738 1.100074)
			(stroke
				(width 0.1524)
				(type default)
			)
			(layer "F.SilkS")
		)
		(fp_poly
			(pts
				(xy -2.2352 -1.001014) (xy -1.533144 -0.649986) (xy -2.2352 -0.298958)
			)
			(stroke
				(width 0)
				(type default)
			)
			(fill yes)
			(layer "F.SilkS")
		)
		(fp_line
			(start -0.674878 -1.100074)
			(end 0.674878 -1.100074)
			(stroke
				(width 0.1)
				(type default)
			)
			(layer "F.Fab")
		)
		(fp_line
			(start -0.674878 1.100074)
			(end -0.674878 -1.100074)
			(stroke
				(width 0.1)
				(type default)
			)
			(layer "F.Fab")
		)
		(fp_line
			(start 0.674878 -1.100074)
			(end 0.674878 1.100074)
			(stroke
				(width 0.1)
				(type default)
			)
			(layer "F.Fab")
		)
		(fp_line
			(start 0.674878 1.100074)
			(end -0.674878 1.100074)
			(stroke
				(width 0.1)
				(type default)
			)
			(layer "F.Fab")
		)
		(fp_poly
			(pts
				(xy -2.2352 -0.298958) (xy -2.2352 -1.001014) (xy -1.533144 -0.649986)
			)
			(stroke
				(width 0)
				(type default)
			)
			(fill yes)
			(layer "F.Fab")
		)
		(pad "1" smd rect
			(at -0.94996 -0.649986 90)
			(size 0.4318 0.508)
			(layers "F.Cu" "F.Mask" "F.Paste")
			(net "GND")
		)
		(pad "2" smd rect
			(at -0.94996 0 90)
			(size 0.4318 0.508)
			(layers "F.Cu" "F.Mask" "F.Paste")
			(net "GPU_3V3IO_RSVD3")
		)
		(pad "3" smd rect
			(at -0.94996 0.649986 90)
			(size 0.4318 0.508)
			(layers "F.Cu" "F.Mask" "F.Paste")
			(net "GPU_3V3IO_RSVD3_ISO")
		)
		(pad "4" smd rect
			(at 0.94996 0.649986 90)
			(size 0.4318 0.508)
			(layers "F.Cu" "F.Mask" "F.Paste")
			(net "GND")
		)
		(pad "5" smd rect
			(at 0.94996 0 90)
			(size 0.4318 0.508)
			(layers "F.Cu" "F.Mask" "F.Paste")
			(net "GPU_3V3IO_RSVD3_N")
		)
		(pad "6" smd rect
			(at 0.94996 -0.649986 90)
			(size 0.4318 0.508)
			(layers "F.Cu" "F.Mask" "F.Paste")
			(net "GPU_3V3IO_RSVD3_N")
		)
	)
	(footprint ""
		(layer "F.Cu")
		(at 16.422878 -16.099536 90)
		(property "Reference" "C806"
			(at 0 0 90)
			(layer "F.SilkS")
			(hide yes)
			(effects
				(font
					(size 1.27 1.27)
				)
			)
		)
		(property "Value" ""
			(at 0 0 90)
			(layer "F.Fab")
			(effects
				(font
					(size 1.27 1.27)
				)
			)
		)
		(duplicate_pad_numbers_are_jumpers no)
		(fp_line
			(start 0.299974 -0.150114)
			(end 0.299974 0.150114)
			(stroke
				(width 0.1)
				(type default)
			)
			(layer "F.Fab")
		)
		(fp_line
			(start -0.299974 -0.150114)
			(end 0.299974 -0.150114)
			(stroke
				(width 0.1)
				(type default)
			)
			(layer "F.Fab")
		)
		(fp_line
			(start 0.299974 0.150114)
			(end -0.299974 0.150114)
			(stroke
				(width 0.1)
				(type default)
			)
			(layer "F.Fab")
		)
		(fp_line
			(start -0.299974 0.150114)
			(end -0.299974 -0.150114)
			(stroke
				(width 0.1)
				(type default)
			)
			(layer "F.Fab")
		)
		(pad "1" smd rect
			(at -0.2667 0 90)
			(size 0.3048 0.381)
			(layers "F.Cu" "F.Mask" "F.Paste")
			(net "P5E_CPU1_PE1_TX_C_DN<15>")
		)
		(pad "2" smd rect
			(at 0.2667 0 90)
			(size 0.3048 0.381)
			(layers "F.Cu" "F.Mask" "F.Paste")
			(net "P5E_CPU1_PE1_TX_DN<15>")
		)
	)
	(footprint ""
		(layer "F.Cu")
		(at 40.506396 -337.471258)
		(property "Reference" "PC414"
			(at 0 0 0)
			(layer "F.SilkS")
			(hide yes)
			(effects
				(font
					(size 1.27 1.27)
				)
			)
		)
		(property "Value" ""
			(at 0 0 0)
			(layer "F.Fab")
			(effects
				(font
					(size 1.27 1.27)
				)
			)
		)
		(duplicate_pad_numbers_are_jumpers no)
		(fp_line
			(start 2.750058 0.999998)
			(end -2.750058 0.999998)
			(stroke
				(width 0.1524)
				(type default)
			)
			(layer "F.SilkS")
		)
		(fp_circle
			(center 0 0.999998)
			(end 2.750058 0.999998)
			(stroke
				(width 0.1524)
				(type default)
			)
			(fill no)
			(layer "F.SilkS")
		)
		(fp_poly
			(pts
				(arc
					(start 2.750058 0.999998)
					(mid 0 3.750056)
					(end -2.750058 0.999998)
				)
			)
			(stroke
				(width 0)
				(type default)
			)
			(fill yes)
			(layer "F.SilkS")
		)
		(fp_circle
			(center 0 0.999998)
			(end 2.750058 0.999998)
			(stroke
				(width 0.1)
				(type default)
			)
			(fill no)
			(layer "F.Fab")
		)
		(pad "1" thru_hole rect
			(at 0 0)
			(size 1.5748 1.5748)
			(drill 1.0668)
			(layers "*.Cu" "*.Mask")
			(remove_unused_layers no)
			(net "PVCCFA_EHV_FIVRA_CPU1")
			(clearance 0)
			(padstack
				(mode front_inner_back)
				(layer "Inner"
					(shape circle)
					(size 1.5748 1.5748)
					(clearance 0)
				)
				(layer "B.Cu"
					(shape rect)
					(size 1.5748 1.5748)
					(clearance 0)
				)
			)
		)
		(pad "2" thru_hole circle
			(at 0 1.999996)
			(size 1.5748 1.5748)
			(drill 1.0668)
			(layers "*.Cu" "*.Mask")
			(remove_unused_layers no)
			(net "GND")
			(clearance 0)
		)
	)
)
